FILE_TYPE = MACRO_DRAWING;
SET COLOR_WIRE YELLOW;
SET COLOR_PROP ORANGE;
SET COLOR_DOT WHITE;
SET COLOR_ARC YELLOW;
SET COLOR_BODY GREEN;
SET COLOR_NOTE PURPLE;
SET PROP_DISPLAY VALUE;
SET PAGE_NUMBER P37;
FORCEADD VCC_CORE..1
(4575 1400);
FORCEPROP 3 LASTPIN (4575 1350) SIG_NAME PVCCFA_EHV_CPU0\g
J 0
(4585 1360);
DISPLAY 0.659574 (4585 1360);
PAINT MONO (4585 1360);
DISPLAY INVISIBLE (4585 1360);
FORCEPROP 1 LAST HDL_POWER PVCCFA_EHV_CPU0
J 1
(4575 1450);
DISPLAY 1.148936 (4575 1450);
PAINT GREEN (4575 1450);
FORCEPROP 2 LAST CDS_LIB logical_power
J 0
(4575 1400);
PAINT MONO (4575 1400);
DISPLAY INVISIBLE (4575 1400);
FORCEPROP 1 LAST PATH I10
J 0
(4625 1425);
DISPLAY 0.872340 (4625 1425);
PAINT AQUA (4625 1425);
DISPLAY INVISIBLE (4625 1425);
FORCEADD VCC_CORE..1
(1325 2200);
FORCEPROP 3 LASTPIN (1325 2150) SIG_NAME PVNN_MAIN_CPU0\g
J 0
(1335 2160);
DISPLAY 0.659574 (1335 2160);
PAINT MONO (1335 2160);
DISPLAY INVISIBLE (1335 2160);
FORCEPROP 1 LAST HDL_POWER PVNN_MAIN_CPU0
J 1
(1325 2250);
DISPLAY 1.148936 (1325 2250);
PAINT GREEN (1325 2250);
FORCEPROP 2 LAST CDS_LIB logical_power
J 0
(1325 2200);
PAINT MONO (1325 2200);
DISPLAY INVISIBLE (1325 2200);
FORCEPROP 1 LAST PATH I11
J 0
(1375 2225);
DISPLAY 0.872340 (1375 2225);
PAINT AQUA (1375 2225);
DISPLAY INVISIBLE (1375 2225);
FORCEADD VCC_CORE..1
(1325 1625);
FORCEPROP 3 LASTPIN (1325 1575) SIG_NAME PVPP_HBM_CPU0\g
J 0
(1335 1585);
DISPLAY 0.659574 (1335 1585);
PAINT MONO (1335 1585);
DISPLAY INVISIBLE (1335 1585);
FORCEPROP 1 LAST HDL_POWER PVPP_HBM_CPU0
J 1
(1325 1675);
DISPLAY 1.148936 (1325 1675);
PAINT GREEN (1325 1675);
FORCEPROP 2 LAST CDS_LIB logical_power
J 0
(1325 1625);
PAINT MONO (1325 1625);
DISPLAY INVISIBLE (1325 1625);
FORCEPROP 1 LAST PATH I12
J 0
(1375 1650);
DISPLAY 0.872340 (1375 1650);
PAINT AQUA (1375 1650);
DISPLAY INVISIBLE (1375 1650);
FORCEADD VCC_CORE..1
(625 1950);
FORCEPROP 3 LASTPIN (625 1900) SIG_NAME P3V3_AUX\g
J 0
(635 1910);
DISPLAY 0.659574 (635 1910);
PAINT MONO (635 1910);
DISPLAY INVISIBLE (635 1910);
FORCEPROP 1 LAST HDL_POWER P3V3_AUX
J 1
(625 2000);
DISPLAY 1.148936 (625 2000);
PAINT GREEN (625 2000);
FORCEPROP 2 LAST CDS_LIB logical_power
J 0
(625 1950);
PAINT MONO (625 1950);
DISPLAY INVISIBLE (625 1950);
FORCEPROP 1 LAST PATH I13
J 0
(675 1975);
DISPLAY 0.872340 (675 1975);
PAINT AQUA (675 1975);
DISPLAY INVISIBLE (675 1975);
FORCEADD UNIVERSAL_GND..1
(625 1325);
FORCEPROP 3 LASTPIN (625 1375) SIG_NAME GND\g
J 0
(635 1385);
DISPLAY 0.659574 (635 1385);
PAINT MONO (635 1385);
DISPLAY INVISIBLE (635 1385);
FORCEPROP 2 LAST CDS_LIB logical_power
J 0
(625 1325);
PAINT MONO (625 1325);
DISPLAY INVISIBLE (625 1325);
FORCEPROP 1 LAST HDL_POWER GND
J 1
(650 1250);
DISPLAY 0.872340 (650 1250);
PAINT GREEN (650 1250);
DISPLAY INVISIBLE (650 1250);
FORCEPROP 1 LAST PATH I14
J 0
(700 1325);
DISPLAY 0.872340 (700 1325);
PAINT AQUA (700 1325);
DISPLAY INVISIBLE (700 1325);
FORCEADD Q_CAP..1
(625 1600);
FORCEPROP 1 LAST PART_NUMBER CH6101MEB01
J 0
(675 1450);
DISPLAY 0.978723 (675 1450);
DISPLAY INVISIBLE (675 1450);
FORCEPROP 1 LAST TOLERANCE 20%
J 0
(675 1550);
DISPLAY 0.978723 (675 1550);
FORCEPROP 1 LAST VALUE 10UF
J 0
(675 1650);
DISPLAY 0.978723 (675 1650);
FORCEPROP 1 LAST MATERIAL X6S
J 0
(675 1500);
DISPLAY 0.978723 (675 1500);
FORCEPROP 1 LAST VOLTAGE 6.3V
J 0
(675 1600);
DISPLAY 0.978723 (675 1600);
FORCEPROP 1 LAST PACK_TYPE C0402
J 0
(675 1400);
DISPLAY 0.978723 (675 1400);
FORCEPROP 1 LAST $LOCATION C1
J 0
(675 1700);
DISPLAY 0.978723 (675 1700);
FORCEPROP 2 LAST CDS_LIB pure_quanta
J 0
(625 1600);
PAINT MONO (625 1600);
DISPLAY INVISIBLE (625 1600);
FORCEPROP 2 LAST CDS_LOCATION C1
J 0
(675 1800);
DISPLAY 1.021277 (675 1800);
DISPLAY INVISIBLE (675 1800);
FORCEPROP 2 LAST $SEC 1
J 0
(675 1800);
DISPLAY 0.680851 (675 1800);
PAINT MONO (675 1800);
DISPLAY INVISIBLE (675 1800);
FORCEPROP 2 LAST CDS_SEC 1
J 0
(675 1800);
DISPLAY 1.021277 (675 1800);
DISPLAY INVISIBLE (675 1800);
FORCEPROP 1 LASTPIN (625 1700) $PN 1
J 0
(635 1680);
DISPLAY 0.787234 (635 1680);
DISPLAY INVISIBLE (635 1680);
FORCEPROP 1 LASTPIN (625 1500) $PN 2
J 0
(635 1480);
DISPLAY 0.787234 (635 1480);
DISPLAY INVISIBLE (635 1480);
FORCEPROP 1 LAST PATH I15
J 0
(675 1750);
DISPLAY 0.978723 (675 1750);
PAINT WHITE (675 1750);
DISPLAY INVISIBLE (675 1750);
FORCEADD VCC_CORE..1
(-3050 4050);
FORCEPROP 3 LASTPIN (-3050 4000) SIG_NAME PVCCIN_CPU0\g
J 0
(-3040 4010);
DISPLAY 0.659574 (-3040 4010);
PAINT MONO (-3040 4010);
DISPLAY INVISIBLE (-3040 4010);
FORCEPROP 1 LAST HDL_POWER PVCCIN_CPU0
J 1
(-3050 4100);
DISPLAY 1.148936 (-3050 4100);
PAINT GREEN (-3050 4100);
FORCEPROP 2 LAST CDS_LIB logical_power
J 0
(-3050 4050);
PAINT MONO (-3050 4050);
DISPLAY INVISIBLE (-3050 4050);
FORCEPROP 1 LAST PATH I2
J 0
(-3000 4075);
DISPLAY 0.872340 (-3000 4075);
PAINT AQUA (-3000 4075);
DISPLAY INVISIBLE (-3000 4075);
FORCEADD VCC_CORE..1
(-150 4050);
FORCEPROP 3 LASTPIN (-150 4000) SIG_NAME PVCCINFAON_CPU0\g
J 0
(-140 4010);
DISPLAY 0.659574 (-140 4010);
PAINT MONO (-140 4010);
DISPLAY INVISIBLE (-140 4010);
FORCEPROP 1 LAST HDL_POWER PVCCINFAON_CPU0
J 1
(-150 4100);
DISPLAY 1.148936 (-150 4100);
PAINT GREEN (-150 4100);
FORCEPROP 2 LAST CDS_LIB logical_power
J 0
(-150 4050);
PAINT MONO (-150 4050);
DISPLAY INVISIBLE (-150 4050);
FORCEPROP 1 LAST PATH I4
J 0
(-100 4075);
DISPLAY 0.872340 (-100 4075);
PAINT AQUA (-100 4075);
DISPLAY INVISIBLE (-100 4075);
FORCEADD VCC_CORE..1
(1325 4050);
FORCEPROP 3 LASTPIN (1325 4000) SIG_NAME PVCCD_HV_CPU0\g
J 0
(1335 4010);
DISPLAY 0.659574 (1335 4010);
PAINT MONO (1335 4010);
DISPLAY INVISIBLE (1335 4010);
FORCEPROP 1 LAST HDL_POWER PVCCD_HV_CPU0
J 1
(1325 4100);
DISPLAY 1.148936 (1325 4100);
PAINT GREEN (1325 4100);
FORCEPROP 2 LAST CDS_LIB logical_power
J 0
(1325 4050);
PAINT MONO (1325 4050);
DISPLAY INVISIBLE (1325 4050);
FORCEPROP 1 LAST PATH I5
J 0
(1375 4075);
DISPLAY 0.872340 (1375 4075);
PAINT AQUA (1375 4075);
DISPLAY INVISIBLE (1375 4075);
FORCEADD VCC_CORE..1
(4225 4500);
FORCEPROP 3 LASTPIN (4225 4450) SIG_NAME PVCCINFAON_CPU0\g
J 0
(4235 4460);
DISPLAY 0.659574 (4235 4460);
PAINT MONO (4235 4460);
DISPLAY INVISIBLE (4235 4460);
FORCEPROP 1 LAST HDL_POWER PVCCINFAON_CPU0
J 1
(4225 4550);
DISPLAY 1.148936 (4225 4550);
PAINT GREEN (4225 4550);
FORCEPROP 2 LAST CDS_LIB logical_power
J 0
(4225 4500);
PAINT MONO (4225 4500);
DISPLAY INVISIBLE (4225 4500);
FORCEPROP 1 LAST PATH I6
J 0
(4275 4525);
DISPLAY 0.872340 (4275 4525);
PAINT AQUA (4275 4525);
DISPLAY INVISIBLE (4275 4525);
FORCEADD SOCKET4677_AZIF0045P001C01CS..28
(-1600 2850);
FORCEPROP 1 LAST PART_NUMBER DGA^7000023
J 0
(-2650 4100);
DISPLAY 0.723404 (-2650 4100);
PAINT GREEN (-2650 4100);
DISPLAY INVISIBLE (-2650 4100);
FORCEPROP 2 LAST PART_TYPE SMLF
J 0
(-2650 4275);
DISPLAY 1.021277 (-2650 4275);
FORCEPROP 1 LAST MATERIAL IO
J 0
(-2650 4025);
DISPLAY 0.723404 (-2650 4025);
PAINT GREEN (-2650 4025);
FORCEPROP 2 LAST VALUE SOCKET4677_AZIF0045-P001C01CS
J 0
(-2650 4225);
DISPLAY 1.021277 (-2650 4225);
FORCEPROP 1 LAST $LOCATION U2
J 0
(-2650 4175);
DISPLAY 0.723404 (-2650 4175);
PAINT GREEN (-2650 4175);
FORCEPROP 0 LASTPIN (-2800 1875) $PN BD91
J 2
(-2810 1885);
DISPLAY 0.680851 (-2810 1885);
PAINT MONO (-2810 1885);
FORCEPROP 0 LASTPIN (-2800 1925) $PN BE86
J 2
(-2810 1935);
DISPLAY 0.680851 (-2810 1935);
PAINT MONO (-2810 1935);
FORCEPROP 0 LASTPIN (-2800 1975) $PN BE88
J 2
(-2810 1985);
DISPLAY 0.680851 (-2810 1985);
PAINT MONO (-2810 1985);
FORCEPROP 0 LASTPIN (-2800 2025) $PN BE90
J 2
(-2810 2035);
DISPLAY 0.680851 (-2810 2035);
PAINT MONO (-2810 2035);
FORCEPROP 0 LASTPIN (-2800 2075) $PN BF85
J 2
(-2810 2085);
DISPLAY 0.680851 (-2810 2085);
PAINT MONO (-2810 2085);
FORCEPROP 0 LASTPIN (-2800 2125) $PN BF87
J 2
(-2810 2135);
DISPLAY 0.680851 (-2810 2135);
PAINT MONO (-2810 2135);
FORCEPROP 0 LASTPIN (-2800 2175) $PN BF89
J 2
(-2810 2185);
DISPLAY 0.680851 (-2810 2185);
PAINT MONO (-2810 2185);
FORCEPROP 0 LASTPIN (-2800 2225) $PN BF91
J 2
(-2810 2235);
DISPLAY 0.680851 (-2810 2235);
PAINT MONO (-2810 2235);
FORCEPROP 0 LASTPIN (-2800 2275) $PN BG84
J 2
(-2810 2285);
DISPLAY 0.680851 (-2810 2285);
PAINT MONO (-2810 2285);
FORCEPROP 0 LASTPIN (-2800 2325) $PN BG86
J 2
(-2810 2335);
DISPLAY 0.680851 (-2810 2335);
PAINT MONO (-2810 2335);
FORCEPROP 0 LASTPIN (-2800 2375) $PN BG88
J 2
(-2810 2385);
DISPLAY 0.680851 (-2810 2385);
PAINT MONO (-2810 2385);
FORCEPROP 0 LASTPIN (-2800 2425) $PN BG90
J 2
(-2810 2435);
DISPLAY 0.680851 (-2810 2435);
PAINT MONO (-2810 2435);
FORCEPROP 0 LASTPIN (-2800 2475) $PN BH85
J 2
(-2810 2485);
DISPLAY 0.680851 (-2810 2485);
PAINT MONO (-2810 2485);
FORCEPROP 0 LASTPIN (-2800 2525) $PN BH87
J 2
(-2810 2535);
DISPLAY 0.680851 (-2810 2535);
PAINT MONO (-2810 2535);
FORCEPROP 0 LASTPIN (-2800 2575) $PN BH89
J 2
(-2810 2585);
DISPLAY 0.680851 (-2810 2585);
PAINT MONO (-2810 2585);
FORCEPROP 0 LASTPIN (-2800 2625) $PN BH91
J 2
(-2810 2635);
DISPLAY 0.680851 (-2810 2635);
PAINT MONO (-2810 2635);
FORCEPROP 0 LASTPIN (-2800 2675) $PN BK81
J 2
(-2810 2685);
DISPLAY 0.680851 (-2810 2685);
PAINT MONO (-2810 2685);
FORCEPROP 0 LASTPIN (-2800 2725) $PN BK83
J 2
(-2810 2735);
DISPLAY 0.680851 (-2810 2735);
PAINT MONO (-2810 2735);
FORCEPROP 0 LASTPIN (-2800 2775) $PN BK85
J 2
(-2810 2785);
DISPLAY 0.680851 (-2810 2785);
PAINT MONO (-2810 2785);
FORCEPROP 0 LASTPIN (-2800 2825) $PN BK87
J 2
(-2810 2835);
DISPLAY 0.680851 (-2810 2835);
PAINT MONO (-2810 2835);
FORCEPROP 0 LASTPIN (-2800 2875) $PN BK89
J 2
(-2810 2885);
DISPLAY 0.680851 (-2810 2885);
PAINT MONO (-2810 2885);
FORCEPROP 0 LASTPIN (-2800 2925) $PN BK91
J 2
(-2810 2935);
DISPLAY 0.680851 (-2810 2935);
PAINT MONO (-2810 2935);
FORCEPROP 0 LASTPIN (-2800 2975) $PN BL80
J 2
(-2810 2985);
DISPLAY 0.680851 (-2810 2985);
PAINT MONO (-2810 2985);
FORCEPROP 0 LASTPIN (-2800 3025) $PN BL82
J 2
(-2810 3035);
DISPLAY 0.680851 (-2810 3035);
PAINT MONO (-2810 3035);
FORCEPROP 0 LASTPIN (-2800 3075) $PN BL84
J 2
(-2810 3085);
DISPLAY 0.680851 (-2810 3085);
PAINT MONO (-2810 3085);
FORCEPROP 0 LASTPIN (-2800 3125) $PN BL86
J 2
(-2810 3135);
DISPLAY 0.680851 (-2810 3135);
PAINT MONO (-2810 3135);
FORCEPROP 0 LASTPIN (-2800 3175) $PN BL88
J 2
(-2810 3185);
DISPLAY 0.680851 (-2810 3185);
PAINT MONO (-2810 3185);
FORCEPROP 0 LASTPIN (-2800 3225) $PN BL90
J 2
(-2810 3235);
DISPLAY 0.680851 (-2810 3235);
PAINT MONO (-2810 3235);
FORCEPROP 0 LASTPIN (-2800 3275) $PN BM79
J 2
(-2810 3285);
DISPLAY 0.680851 (-2810 3285);
PAINT MONO (-2810 3285);
FORCEPROP 0 LASTPIN (-2800 3325) $PN BM81
J 2
(-2810 3335);
DISPLAY 0.680851 (-2810 3335);
PAINT MONO (-2810 3335);
FORCEPROP 0 LASTPIN (-2800 3375) $PN BM83
J 2
(-2810 3385);
DISPLAY 0.680851 (-2810 3385);
PAINT MONO (-2810 3385);
FORCEPROP 0 LASTPIN (-2800 3425) $PN BM85
J 2
(-2810 3435);
DISPLAY 0.680851 (-2810 3435);
PAINT MONO (-2810 3435);
FORCEPROP 0 LASTPIN (-2800 3475) $PN BM87
J 2
(-2810 3485);
DISPLAY 0.680851 (-2810 3485);
PAINT MONO (-2810 3485);
FORCEPROP 0 LASTPIN (-2800 3525) $PN BM89
J 2
(-2810 3535);
DISPLAY 0.680851 (-2810 3535);
PAINT MONO (-2810 3535);
FORCEPROP 0 LASTPIN (-2800 3575) $PN BM91
J 2
(-2810 3585);
DISPLAY 0.680851 (-2810 3585);
PAINT MONO (-2810 3585);
FORCEPROP 0 LASTPIN (-2800 3625) $PN BN33
J 2
(-2810 3635);
DISPLAY 0.680851 (-2810 3635);
PAINT MONO (-2810 3635);
FORCEPROP 0 LASTPIN (-2800 3675) $PN BN35
J 2
(-2810 3685);
DISPLAY 0.680851 (-2810 3685);
PAINT MONO (-2810 3685);
FORCEPROP 0 LASTPIN (-2800 3725) $PN BN37
J 2
(-2810 3735);
DISPLAY 0.680851 (-2810 3735);
PAINT MONO (-2810 3735);
FORCEPROP 0 LASTPIN (-2800 3775) $PN BN39
J 2
(-2810 3785);
DISPLAY 0.680851 (-2810 3785);
PAINT MONO (-2810 3785);
FORCEPROP 0 LASTPIN (-2800 3825) $PN BN41
J 2
(-2810 3835);
DISPLAY 0.680851 (-2810 3835);
PAINT MONO (-2810 3835);
FORCEPROP 0 LASTPIN (-400 3575) $PN AY18
J 0
(-390 3585);
DISPLAY 0.680851 (-390 3585);
PAINT MONO (-390 3585);
FORCEPROP 0 LASTPIN (-400 3825) $PN BA15
J 0
(-390 3835);
DISPLAY 0.680851 (-390 3835);
PAINT MONO (-390 3835);
FORCEPROP 0 LASTPIN (-400 3275) $PN BC60
J 0
(-390 3285);
DISPLAY 0.680851 (-390 3285);
PAINT MONO (-390 3285);
FORCEPROP 0 LASTPIN (-400 3425) $PN BE15
J 0
(-390 3435);
DISPLAY 0.680851 (-390 3435);
PAINT MONO (-390 3435);
FORCEPROP 0 LASTPIN (-400 3775) $PN BE60
J 0
(-390 3785);
DISPLAY 0.680851 (-390 3785);
PAINT MONO (-390 3785);
FORCEPROP 0 LASTPIN (-400 3325) $PN BG60
J 0
(-390 3335);
DISPLAY 0.680851 (-390 3335);
PAINT MONO (-390 3335);
FORCEPROP 0 LASTPIN (-400 3475) $PN BJ15
J 0
(-390 3485);
DISPLAY 0.680851 (-390 3485);
PAINT MONO (-390 3485);
FORCEPROP 0 LASTPIN (-400 3225) $PN BJ60
J 0
(-390 3235);
DISPLAY 0.680851 (-390 3235);
PAINT MONO (-390 3235);
FORCEPROP 0 LASTPIN (-400 3375) $PN BK61
J 0
(-390 3385);
DISPLAY 0.680851 (-390 3385);
PAINT MONO (-390 3385);
FORCEPROP 0 LASTPIN (-400 3525) $PN BN15
J 0
(-390 3535);
DISPLAY 0.680851 (-390 3535);
PAINT MONO (-390 3535);
FORCEPROP 0 LASTPIN (-400 3175) $PN CA15
J 0
(-390 3185);
DISPLAY 0.680851 (-390 3185);
PAINT MONO (-390 3185);
FORCEPROP 0 LASTPIN (-400 3725) $PN CE19
J 0
(-390 3735);
DISPLAY 0.680851 (-390 3735);
PAINT MONO (-390 3735);
FORCEPROP 0 LASTPIN (-400 3025) $PN CJ11
J 0
(-390 3035);
DISPLAY 0.680851 (-390 3035);
PAINT MONO (-390 3035);
FORCEPROP 0 LASTPIN (-400 3075) $PN CJ19
J 0
(-390 3085);
DISPLAY 0.680851 (-390 3085);
PAINT MONO (-390 3085);
FORCEPROP 0 LASTPIN (-400 3125) $PN CN19
J 0
(-390 3135);
DISPLAY 0.680851 (-390 3135);
PAINT MONO (-390 3135);
FORCEPROP 0 LASTPIN (-400 2875) $PN CP63
J 0
(-390 2885);
DISPLAY 0.680851 (-390 2885);
PAINT MONO (-390 2885);
FORCEPROP 0 LASTPIN (-400 2975) $PN CT63
J 0
(-390 2985);
DISPLAY 0.680851 (-390 2985);
PAINT MONO (-390 2985);
FORCEPROP 0 LASTPIN (-400 2825) $PN CV61
J 0
(-390 2835);
DISPLAY 0.680851 (-390 2835);
PAINT MONO (-390 2835);
FORCEPROP 0 LASTPIN (-400 3675) $PN CV63
J 0
(-390 3685);
DISPLAY 0.680851 (-390 3685);
PAINT MONO (-390 3685);
FORCEPROP 0 LASTPIN (-400 2925) $PN CW62
J 0
(-390 2935);
DISPLAY 0.680851 (-390 2935);
PAINT MONO (-390 2935);
FORCEPROP 0 LASTPIN (-400 2725) $PN DA21
J 0
(-390 2735);
DISPLAY 0.680851 (-390 2735);
PAINT MONO (-390 2735);
FORCEPROP 2 LAST CDS_LIB pure_quanta
J 0
(-1600 2850);
DISPLAY INVISIBLE (-1600 2850);
FORCEPROP 1 LAST NEEDS_NO_SIZE TRUE
J 0
(-1600 2850);
DISPLAY 0.723404 (-1600 2850);
PAINT GREEN (-1600 2850);
DISPLAY INVISIBLE (-1600 2850);
FORCEPROP 1 LAST CDS_LMAN_SYM_OUTLINE -1050,1150,1050,-1100
J 0
(-1600 2850);
DISPLAY 0.468085 (-1600 2850);
PAINT GREEN (-1600 2850);
DISPLAY INVISIBLE (-1600 2850);
FORCEPROP 2 LAST CDS_LOCATION U2
J 0
(-2650 4325);
DISPLAY 1.021277 (-2650 4325);
DISPLAY INVISIBLE (-2650 4325);
FORCEPROP 0 LAST $SEC 28
J 0
(-2650 4325);
DISPLAY 0.680851 (-2650 4325);
PAINT MONO (-2650 4325);
DISPLAY INVISIBLE (-2650 4325);
FORCEPROP 2 LAST CDS_SEC 28
J 0
(-2650 4325);
DISPLAY 1.021277 (-2650 4325);
DISPLAY INVISIBLE (-2650 4325);
FORCEPROP 1 LAST PATH I7
J 0
(-1600 2850);
DISPLAY 0.723404 (-1600 2850);
PAINT GREEN (-1600 2850);
DISPLAY INVISIBLE (-1600 2850);
FORCEADD SOCKET4677_AZIF0045P001C01CS..29
(2775 2450);
FORCEPROP 1 LAST PART_NUMBER DGA^7000023
J 0
(1725 4350);
DISPLAY 0.723404 (1725 4350);
PAINT GREEN (1725 4350);
DISPLAY INVISIBLE (1725 4350);
FORCEPROP 2 LAST PART_TYPE SMLF
J 0
(1725 4525);
DISPLAY 1.021277 (1725 4525);
FORCEPROP 1 LAST MATERIAL IO
J 0
(1725 4275);
DISPLAY 0.723404 (1725 4275);
PAINT GREEN (1725 4275);
FORCEPROP 2 LAST VALUE SOCKET4677_AZIF0045-P001C01CS
J 0
(1725 4475);
DISPLAY 1.021277 (1725 4475);
FORCEPROP 1 LAST $LOCATION U2
J 0
(1725 4425);
DISPLAY 0.723404 (1725 4425);
PAINT GREEN (1725 4425);
FORCEPROP 0 LASTPIN (1575 2425) $PN AT36
J 2
(1565 2435);
DISPLAY 0.680851 (1565 2435);
PAINT MONO (1565 2435);
FORCEPROP 0 LASTPIN (1575 2475) $PN AT55
J 2
(1565 2485);
DISPLAY 0.680851 (1565 2485);
PAINT MONO (1565 2485);
FORCEPROP 0 LASTPIN (1575 2525) $PN AU3
J 2
(1565 2535);
DISPLAY 0.680851 (1565 2535);
PAINT MONO (1565 2535);
FORCEPROP 0 LASTPIN (1575 2625) $PN AU35
J 2
(1565 2635);
DISPLAY 0.680851 (1565 2635);
PAINT MONO (1565 2635);
FORCEPROP 0 LASTPIN (1575 2675) $PN AU54
J 2
(1565 2685);
DISPLAY 0.680851 (1565 2685);
PAINT MONO (1565 2685);
FORCEPROP 0 LASTPIN (1575 2575) $PN AU7
J 2
(1565 2585);
DISPLAY 0.680851 (1565 2585);
PAINT MONO (1565 2585);
FORCEPROP 0 LASTPIN (1575 2725) $PN AV34
J 2
(1565 2735);
DISPLAY 0.680851 (1565 2735);
PAINT MONO (1565 2735);
FORCEPROP 0 LASTPIN (1575 2775) $PN AV36
J 2
(1565 2785);
DISPLAY 0.680851 (1565 2785);
PAINT MONO (1565 2785);
FORCEPROP 0 LASTPIN (1575 2825) $PN AV53
J 2
(1565 2835);
DISPLAY 0.680851 (1565 2835);
PAINT MONO (1565 2835);
FORCEPROP 0 LASTPIN (1575 2875) $PN AV55
J 2
(1565 2885);
DISPLAY 0.680851 (1565 2885);
PAINT MONO (1565 2885);
FORCEPROP 0 LASTPIN (1575 2925) $PN BA3
J 2
(1565 2935);
DISPLAY 0.680851 (1565 2935);
PAINT MONO (1565 2935);
FORCEPROP 0 LASTPIN (1575 2975) $PN BA7
J 2
(1565 2985);
DISPLAY 0.680851 (1565 2985);
PAINT MONO (1565 2985);
FORCEPROP 0 LASTPIN (1575 3125) $PN BE11
J 2
(1565 3135);
DISPLAY 0.680851 (1565 3135);
PAINT MONO (1565 3135);
FORCEPROP 0 LASTPIN (1575 3025) $PN BE3
J 2
(1565 3035);
DISPLAY 0.680851 (1565 3035);
PAINT MONO (1565 3035);
FORCEPROP 0 LASTPIN (1575 3075) $PN BE7
J 2
(1565 3085);
DISPLAY 0.680851 (1565 3085);
PAINT MONO (1565 3085);
FORCEPROP 0 LASTPIN (1575 3275) $PN BJ11
J 2
(1565 3285);
DISPLAY 0.680851 (1565 3285);
PAINT MONO (1565 3285);
FORCEPROP 0 LASTPIN (1575 3175) $PN BJ3
J 2
(1565 3185);
DISPLAY 0.680851 (1565 3185);
PAINT MONO (1565 3185);
FORCEPROP 0 LASTPIN (1575 3225) $PN BJ7
J 2
(1565 3235);
DISPLAY 0.680851 (1565 3235);
PAINT MONO (1565 3235);
FORCEPROP 0 LASTPIN (1575 3325) $PN BN7
J 2
(1565 3335);
DISPLAY 0.680851 (1565 3335);
PAINT MONO (1565 3335);
FORCEPROP 0 LASTPIN (1575 3375) $PN CA7
J 2
(1565 3385);
DISPLAY 0.680851 (1565 3385);
PAINT MONO (1565 3385);
FORCEPROP 0 LASTPIN (1575 3425) $PN CE7
J 2
(1565 3435);
DISPLAY 0.680851 (1565 3435);
PAINT MONO (1565 3435);
FORCEPROP 0 LASTPIN (1575 3475) $PN CW35
J 2
(1565 3485);
DISPLAY 0.680851 (1565 3485);
PAINT MONO (1565 3485);
FORCEPROP 0 LASTPIN (1575 3525) $PN CW37
J 2
(1565 3535);
DISPLAY 0.680851 (1565 3535);
PAINT MONO (1565 3535);
FORCEPROP 0 LASTPIN (1575 3575) $PN CW52
J 2
(1565 3585);
DISPLAY 0.680851 (1565 3585);
PAINT MONO (1565 3585);
FORCEPROP 0 LASTPIN (1575 3625) $PN CW54
J 2
(1565 3635);
DISPLAY 0.680851 (1565 3635);
PAINT MONO (1565 3635);
FORCEPROP 0 LASTPIN (1575 3675) $PN CW56
J 2
(1565 3685);
DISPLAY 0.680851 (1565 3685);
PAINT MONO (1565 3685);
FORCEPROP 0 LASTPIN (1575 3725) $PN CY34
J 2
(1565 3735);
DISPLAY 0.680851 (1565 3735);
PAINT MONO (1565 3735);
FORCEPROP 0 LASTPIN (1575 3775) $PN CY36
J 2
(1565 3785);
DISPLAY 0.680851 (1565 3785);
PAINT MONO (1565 3785);
FORCEPROP 0 LASTPIN (1575 3825) $PN CY53
J 2
(1565 3835);
DISPLAY 0.680851 (1565 3835);
PAINT MONO (1565 3835);
FORCEPROP 0 LASTPIN (3975 925) $PN AA3
J 0
(3985 935);
DISPLAY 0.680851 (3985 935);
PAINT MONO (3985 935);
FORCEPROP 0 LASTPIN (3975 975) $PN AE3
J 0
(3985 985);
DISPLAY 0.680851 (3985 985);
PAINT MONO (3985 985);
FORCEPROP 0 LASTPIN (3975 1025) $PN AJ3
J 0
(3985 1035);
DISPLAY 0.680851 (3985 1035);
PAINT MONO (3985 1035);
FORCEPROP 0 LASTPIN (3975 1075) $PN AN3
J 0
(3985 1085);
DISPLAY 0.680851 (3985 1085);
PAINT MONO (3985 1085);
FORCEPROP 0 LASTPIN (3975 1125) $PN AT61
J 0
(3985 1135);
DISPLAY 0.680851 (3985 1135);
PAINT MONO (3985 1135);
FORCEPROP 0 LASTPIN (3975 1175) $PN AU60
J 0
(3985 1185);
DISPLAY 0.680851 (3985 1185);
PAINT MONO (3985 1185);
FORCEPROP 0 LASTPIN (3975 1225) $PN AV61
J 0
(3985 1235);
DISPLAY 0.680851 (3985 1235);
PAINT MONO (3985 1235);
FORCEPROP 0 LASTPIN (3975 1275) $PN AW60
J 0
(3985 1285);
DISPLAY 0.680851 (3985 1285);
PAINT MONO (3985 1285);
FORCEPROP 0 LASTPIN (3975 825) $PN N3
J 0
(3985 835);
DISPLAY 0.680851 (3985 835);
PAINT MONO (3985 835);
FORCEPROP 0 LASTPIN (3975 875) $PN U3
J 0
(3985 885);
DISPLAY 0.680851 (3985 885);
PAINT MONO (3985 885);
FORCEPROP 0 LASTPIN (3975 2175) $PN CE15
J 0
(3985 2185);
DISPLAY 0.680851 (3985 2185);
PAINT MONO (3985 2185);
FORCEPROP 0 LASTPIN (3975 2325) $PN CJ15
J 0
(3985 2335);
DISPLAY 0.680851 (3985 2335);
PAINT MONO (3985 2335);
FORCEPROP 0 LASTPIN (3975 2225) $PN CJ3
J 0
(3985 2235);
DISPLAY 0.680851 (3985 2235);
PAINT MONO (3985 2235);
FORCEPROP 0 LASTPIN (3975 2275) $PN CJ7
J 0
(3985 2285);
DISPLAY 0.680851 (3985 2285);
PAINT MONO (3985 2285);
FORCEPROP 0 LASTPIN (3975 2475) $PN CN11
J 0
(3985 2485);
DISPLAY 0.680851 (3985 2485);
PAINT MONO (3985 2485);
FORCEPROP 0 LASTPIN (3975 2525) $PN CN15
J 0
(3985 2535);
DISPLAY 0.680851 (3985 2535);
PAINT MONO (3985 2535);
FORCEPROP 0 LASTPIN (3975 2375) $PN CN3
J 0
(3985 2385);
DISPLAY 0.680851 (3985 2385);
PAINT MONO (3985 2385);
FORCEPROP 0 LASTPIN (3975 2575) $PN CN64
J 0
(3985 2585);
DISPLAY 0.680851 (3985 2585);
PAINT MONO (3985 2585);
FORCEPROP 0 LASTPIN (3975 2625) $PN CN66
J 0
(3985 2635);
DISPLAY 0.680851 (3985 2635);
PAINT MONO (3985 2635);
FORCEPROP 0 LASTPIN (3975 2425) $PN CN7
J 0
(3985 2435);
DISPLAY 0.680851 (3985 2435);
PAINT MONO (3985 2435);
FORCEPROP 0 LASTPIN (3975 2675) $PN CP65
J 0
(3985 2685);
DISPLAY 0.680851 (3985 2685);
PAINT MONO (3985 2685);
FORCEPROP 0 LASTPIN (3975 2725) $PN CP67
J 0
(3985 2735);
DISPLAY 0.680851 (3985 2735);
PAINT MONO (3985 2735);
FORCEPROP 0 LASTPIN (3975 2825) $PN CT65
J 0
(3985 2835);
DISPLAY 0.680851 (3985 2835);
PAINT MONO (3985 2835);
FORCEPROP 0 LASTPIN (3975 2875) $PN CT67
J 0
(3985 2885);
DISPLAY 0.680851 (3985 2885);
PAINT MONO (3985 2885);
FORCEPROP 0 LASTPIN (3975 3025) $PN CU11
J 0
(3985 3035);
DISPLAY 0.680851 (3985 3035);
PAINT MONO (3985 3035);
FORCEPROP 0 LASTPIN (3975 3075) $PN CU15
J 0
(3985 3085);
DISPLAY 0.680851 (3985 3085);
PAINT MONO (3985 3085);
FORCEPROP 0 LASTPIN (3975 2925) $PN CU3
J 0
(3985 2935);
DISPLAY 0.680851 (3985 2935);
PAINT MONO (3985 2935);
FORCEPROP 0 LASTPIN (3975 3125) $PN CU64
J 0
(3985 3135);
DISPLAY 0.680851 (3985 3135);
PAINT MONO (3985 3135);
FORCEPROP 0 LASTPIN (3975 2975) $PN CU7
J 0
(3985 2985);
DISPLAY 0.680851 (3985 2985);
PAINT MONO (3985 2985);
FORCEPROP 0 LASTPIN (3975 3175) $PN CV65
J 0
(3985 3185);
DISPLAY 0.680851 (3985 3185);
PAINT MONO (3985 3185);
FORCEPROP 0 LASTPIN (3975 3225) $PN CV67
J 0
(3985 3235);
DISPLAY 0.680851 (3985 3235);
PAINT MONO (3985 3235);
FORCEPROP 0 LASTPIN (3975 3325) $PN CW66
J 0
(3985 3335);
DISPLAY 0.680851 (3985 3335);
PAINT MONO (3985 3335);
FORCEPROP 0 LASTPIN (3975 3375) $PN CY65
J 0
(3985 3385);
DISPLAY 0.680851 (3985 3385);
PAINT MONO (3985 3385);
FORCEPROP 0 LASTPIN (3975 3425) $PN CY67
J 0
(3985 3435);
DISPLAY 0.680851 (3985 3435);
PAINT MONO (3985 3435);
FORCEPROP 0 LASTPIN (3975 3575) $PN DA11
J 0
(3985 3585);
DISPLAY 0.680851 (3985 3585);
PAINT MONO (3985 3585);
FORCEPROP 0 LASTPIN (3975 3625) $PN DA15
J 0
(3985 3635);
DISPLAY 0.680851 (3985 3635);
PAINT MONO (3985 3635);
FORCEPROP 0 LASTPIN (3975 3675) $PN DA64
J 0
(3985 3685);
DISPLAY 0.680851 (3985 3685);
PAINT MONO (3985 3685);
FORCEPROP 0 LASTPIN (3975 3825) $PN DE11
J 0
(3985 3835);
DISPLAY 0.680851 (3985 3835);
PAINT MONO (3985 3835);
FORCEPROP 0 LASTPIN (3975 3875) $PN DE15
J 0
(3985 3885);
DISPLAY 0.680851 (3985 3885);
PAINT MONO (3985 3885);
FORCEPROP 0 LASTPIN (3975 3725) $PN DE3
J 0
(3985 3735);
DISPLAY 0.680851 (3985 3735);
PAINT MONO (3985 3735);
FORCEPROP 0 LASTPIN (3975 4075) $PN DJ15
J 0
(3985 4085);
DISPLAY 0.680851 (3985 4085);
PAINT MONO (3985 4085);
FORCEPROP 0 LASTPIN (3975 3925) $PN DJ3
J 0
(3985 3935);
DISPLAY 0.680851 (3985 3935);
PAINT MONO (3985 3935);
FORCEPROP 0 LASTPIN (3975 3975) $PN DJ7
J 0
(3985 3985);
DISPLAY 0.680851 (3985 3985);
PAINT MONO (3985 3985);
FORCEPROP 0 LASTPIN (3975 2775) $PN CR66
J 0
(3985 2785);
DISPLAY 0.680851 (3985 2785);
PAINT MONO (3985 2785);
FORCEPROP 0 LASTPIN (3975 3275) $PN CW64
J 0
(3985 3285);
DISPLAY 0.680851 (3985 3285);
PAINT MONO (3985 3285);
FORCEPROP 0 LASTPIN (3975 3475) $PN DA3
J 0
(3985 3485);
DISPLAY 0.680851 (3985 3485);
PAINT MONO (3985 3485);
FORCEPROP 0 LASTPIN (3975 3525) $PN DA7
J 0
(3985 3535);
DISPLAY 0.680851 (3985 3535);
PAINT MONO (3985 3535);
FORCEPROP 0 LASTPIN (3975 3775) $PN DE7
J 0
(3985 3785);
DISPLAY 0.680851 (3985 3785);
PAINT MONO (3985 3785);
FORCEPROP 0 LASTPIN (3975 4025) $PN DJ11
J 0
(3985 4035);
DISPLAY 0.680851 (3985 4035);
PAINT MONO (3985 4035);
FORCEPROP 0 LASTPIN (1575 2025) $PN BA19
J 2
(1565 2035);
DISPLAY 0.680851 (1565 2035);
PAINT MONO (1565 2035);
FORCEPROP 0 LASTPIN (1575 2075) $PN BE19
J 2
(1565 2085);
DISPLAY 0.680851 (1565 2085);
PAINT MONO (1565 2085);
FORCEPROP 0 LASTPIN (3975 1925) $PN BJ19
J 0
(3985 1935);
DISPLAY 0.680851 (3985 1935);
PAINT MONO (3985 1935);
FORCEPROP 0 LASTPIN (3975 1975) $PN BN19
J 0
(3985 1985);
DISPLAY 0.680851 (3985 1985);
PAINT MONO (3985 1985);
FORCEPROP 0 LASTPIN (1575 1475) $PN CF67
J 2
(1565 1485);
DISPLAY 0.680851 (1565 1485);
PAINT MONO (1565 1485);
FORCEPROP 0 LASTPIN (1575 1425) $PN CE68
J 2
(1565 1435);
DISPLAY 0.680851 (1565 1435);
PAINT MONO (1565 1435);
FORCEPROP 0 LASTPIN (1575 1375) $PN CD67
J 2
(1565 1385);
DISPLAY 0.680851 (1565 1385);
PAINT MONO (1565 1385);
FORCEPROP 0 LASTPIN (1575 1325) $PN CC68
J 2
(1565 1335);
DISPLAY 0.680851 (1565 1335);
PAINT MONO (1565 1335);
FORCEPROP 0 LASTPIN (1575 1825) $PN BC21
J 2
(1565 1835);
DISPLAY 0.680851 (1565 1835);
PAINT MONO (1565 1835);
FORCEPROP 0 LASTPIN (1575 1775) $PN BA21
J 2
(1565 1785);
DISPLAY 0.680851 (1565 1785);
PAINT MONO (1565 1785);
FORCEPROP 0 LASTPIN (1575 1525) $PN CG68
J 2
(1565 1535);
DISPLAY 0.680851 (1565 1535);
PAINT MONO (1565 1535);
FORCEPROP 2 LAST CDS_LIB pure_quanta
J 0
(2775 2450);
DISPLAY INVISIBLE (2775 2450);
FORCEPROP 1 LAST NEEDS_NO_SIZE TRUE
J 0
(2775 2450);
DISPLAY 0.723404 (2775 2450);
PAINT GREEN (2775 2450);
DISPLAY INVISIBLE (2775 2450);
FORCEPROP 1 LAST CDS_LMAN_SYM_OUTLINE -1050,1800,1050,-1750
J 0
(2775 2450);
DISPLAY 0.468085 (2775 2450);
PAINT GREEN (2775 2450);
DISPLAY INVISIBLE (2775 2450);
FORCEPROP 2 LAST CDS_LOCATION U2
J 0
(1725 4575);
DISPLAY 1.021277 (1725 4575);
DISPLAY INVISIBLE (1725 4575);
FORCEPROP 0 LAST $SEC 29
J 0
(1725 4575);
DISPLAY 0.680851 (1725 4575);
PAINT MONO (1725 4575);
DISPLAY INVISIBLE (1725 4575);
FORCEPROP 2 LAST CDS_SEC 29
J 0
(1725 4575);
DISPLAY 1.021277 (1725 4575);
DISPLAY INVISIBLE (1725 4575);
FORCEPROP 1 LAST PATH I8
J 0
(2775 2450);
DISPLAY 0.723404 (2775 2450);
PAINT GREEN (2775 2450);
DISPLAY INVISIBLE (2775 2450);
FORCEADD VCC_CORE..1
(4575 2050);
FORCEPROP 3 LASTPIN (4575 2000) SIG_NAME PVNN_MAIN_CPU0\g
J 0
(4585 2010);
DISPLAY 0.659574 (4585 2010);
PAINT MONO (4585 2010);
DISPLAY INVISIBLE (4585 2010);
FORCEPROP 1 LAST HDL_POWER PVNN_MAIN_CPU0
J 1
(4575 2100);
DISPLAY 1.148936 (4575 2100);
PAINT GREEN (4575 2100);
FORCEPROP 2 LAST CDS_LIB logical_power
J 0
(4575 2050);
PAINT MONO (4575 2050);
DISPLAY INVISIBLE (4575 2050);
FORCEPROP 1 LAST PATH I9
J 0
(4625 2075);
DISPLAY 0.872340 (4625 2075);
PAINT AQUA (4625 2075);
DISPLAY INVISIBLE (4625 2075);
FORCEADD QUANTA_TITLE_BLOCK_C..1
(5400 -1200);
FORCEPROP 0 LAST CDS_CON_LAST_MODIFIED Fri Aug 25 14:00:20 2023
J 0
(3515 -1185);
PAINT MONO (3515 -1185);
DISPLAY INVISIBLE (3515 -1185);
FORCEPROP 2 LAST CUSTOM_TXT_CDS <XR_PAGE_TITLE>
J 0
(-2490 4050);
DISPLAY 0.638298 (-2490 4050);
PAINT PINK (-2490 4050);
DISPLAY INVISIBLE (-2490 4050);
FORCEPROP 2 LAST CUSTOM_TXT_CDS <CON_PAGE_NUM> OF <CON_TOTAL_PAGES>
J 0
(4975 -1175);
DISPLAY 0.978723 (4975 -1175);
FORCEPROP 2 LAST CUSTOM_TXT_CDS <CON_LAST_MODIFIED>
J 0
(3575 -1175);
DISPLAY 0.978723 (3575 -1175);
FORCEPROP 2 LAST CUSTOM_TXT_CDS <Q_REV>
J 0
(5216 -1097);
DISPLAY 1.212766 (5216 -1097);
FORCEPROP 2 LAST CUSTOM_TXT_CDS <Q_NUMBER>
J 0
(3997 -1097);
DISPLAY 1.212766 (3997 -1097);
FORCEPROP 2 LAST CUSTOM_TXT_CDS <Q_PROJ>
J 0
(3018 -1098);
DISPLAY 1.212766 (3018 -1098);
FORCEPROP 1 LAST CUSTOM_TXT_CDS <NAME_2>
J 0
(2225 -1150);
FORCEPROP 1 LAST CUSTOM_TXT_CDS <NAME_1>
J 0
(2225 -1025);
FORCEPROP 1 LAST Q_TITLE SPR CPU0 POWER - VCCIN/VCCINFAON (25)
J 0
(-3966 -1174);
DISPLAY 1.957447 (-3966 -1174);
PAINT GREEN (-3966 -1174);
FORCEPROP 1 LAST Q_DEPT 
J 1
(1637 -1151);
DISPLAY 1.957447 (1637 -1151);
PAINT GREEN (1637 -1151);
FORCEPROP 2 LAST PAGE_BORDER TRUE
J 0
(-2490 4050);
DISPLAY 0.638298 (-2490 4050);
PAINT PINK (-2490 4050);
DISPLAY INVISIBLE (-2490 4050);
FORCEPROP 1 LAST CDS_LMAN_SYM_OUTLINE -9475,6775,100,-125
J 0
(5400 -1200);
DISPLAY 0.468085 (5400 -1200);
PAINT GREEN (5400 -1200);
DISPLAY INVISIBLE (5400 -1200);
FORCEPROP 2 LAST CDS_LIB pure_quanta
J 0
(5400 -1200);
PAINT MONO (5400 -1200);
DISPLAY INVISIBLE (5400 -1200);
FORCEPROP 2 LAST CDS_XR_PAGE_TITLE CR-37 : @S9S_MB_2U_LIB.S9S_MB_2U(SCH_1):PAGE37
J 0
(-2490 4050);
DISPLAY 0.638298 (-2490 4050);
PAINT PINK (-2490 4050);
DISPLAY INVISIBLE (-2490 4050);
FORCEPROP 1 LAST COMMENT_BODY TRUE
J 0
(5412 -1213);
DISPLAY 0.978723 (5412 -1213);
PAINT GREEN (5412 -1213);
DISPLAY INVISIBLE (5412 -1213);
WIRE 16 -1 (4575 2000)(4575 1925);
WIRE 16 -1 (4225 4450)(4225 4075);
WIRE 16 -1 (1325 4000)(1325 3825);
WIRE 16 -1 (-150 4000)(-150 3825);
WIRE 16 -1 (-3050 4000)(-3050 3825);
WIRE 16 -1 (625 1900)(625 1825);
WIRE 16 -1 (1325 1575)(1325 1525);
WIRE 16 -1 (1325 2150)(1325 2075);
WIRE 16 -1 (4575 1350)(4575 1275);
WIRE 16 -1 (625 1375)(625 1500);
WIRE 16 -1 (-150 3825)(-400 3825);
WIRE 16 -1 (-150 3775)(-400 3775);
WIRE 16 -1 (-150 3825)(-150 3775);
WIRE 16 -1 (-150 3725)(-400 3725);
WIRE 16 -1 (-150 3775)(-150 3725);
WIRE 16 -1 (-150 3675)(-400 3675);
WIRE 16 -1 (-150 3725)(-150 3675);
WIRE 16 -1 (-150 3575)(-400 3575);
WIRE 16 -1 (-150 3575)(-150 3675);
WIRE 16 -1 (-150 3525)(-400 3525);
WIRE 16 -1 (-150 3575)(-150 3525);
WIRE 16 -1 (-150 3475)(-400 3475);
WIRE 16 -1 (-150 3525)(-150 3475);
WIRE 16 -1 (-150 3425)(-400 3425);
WIRE 16 -1 (-150 3475)(-150 3425);
WIRE 16 -1 (-150 3375)(-400 3375);
WIRE 16 -1 (-150 3425)(-150 3375);
WIRE 16 -1 (-150 3325)(-400 3325);
WIRE 16 -1 (-150 3375)(-150 3325);
WIRE 16 -1 (-150 3275)(-400 3275);
WIRE 16 -1 (-150 3325)(-150 3275);
WIRE 16 -1 (-150 3225)(-400 3225);
WIRE 16 -1 (-150 3275)(-150 3225);
WIRE 16 -1 (-150 3175)(-400 3175);
WIRE 16 -1 (-150 3225)(-150 3175);
WIRE 16 -1 (-400 3125)(-150 3125);
WIRE 16 -1 (-150 3175)(-150 3125);
WIRE 16 -1 (-400 3075)(-150 3075);
WIRE 16 -1 (-150 3125)(-150 3075);
WIRE 16 -1 (-400 3025)(-150 3025);
WIRE 16 -1 (-150 3075)(-150 3025);
WIRE 16 -1 (-400 2975)(-150 2975);
WIRE 16 -1 (-150 3025)(-150 2975);
WIRE 16 -1 (-400 2925)(-150 2925);
WIRE 16 -1 (-150 2975)(-150 2925);
WIRE 16 -1 (-400 2875)(-150 2875);
WIRE 16 -1 (-150 2925)(-150 2875);
WIRE 16 -1 (-400 2825)(-150 2825);
WIRE 16 -1 (-150 2875)(-150 2825);
WIRE 16 -1 (-150 2725)(-150 2825);
WIRE 16 -1 (-400 2725)(-150 2725);
WIRE 16 -1 (1575 3825)(1325 3825);
WIRE 16 -1 (1325 3825)(1325 3775);
WIRE 16 -1 (1575 3775)(1325 3775);
WIRE 16 -1 (1325 3775)(1325 3725);
WIRE 16 -1 (1575 3725)(1325 3725);
WIRE 16 -1 (1325 3725)(1325 3675);
WIRE 16 -1 (1575 3675)(1325 3675);
WIRE 16 -1 (1325 3675)(1325 3625);
WIRE 16 -1 (1575 3625)(1325 3625);
WIRE 16 -1 (1325 3625)(1325 3575);
WIRE 16 -1 (1575 3575)(1325 3575);
WIRE 16 -1 (1325 3575)(1325 3525);
WIRE 16 -1 (1575 3525)(1325 3525);
WIRE 16 -1 (1325 3525)(1325 3475);
WIRE 16 -1 (1575 3475)(1325 3475);
WIRE 16 -1 (1325 3475)(1325 3425);
WIRE 16 -1 (1575 3425)(1325 3425);
WIRE 16 -1 (1325 3425)(1325 3375);
WIRE 16 -1 (1325 3375)(1575 3375);
WIRE 16 -1 (1325 3375)(1325 3325);
WIRE 16 -1 (1325 3325)(1575 3325);
WIRE 16 -1 (1325 3325)(1325 3275);
WIRE 16 -1 (1575 3275)(1325 3275);
WIRE 16 -1 (1325 3275)(1325 3225);
WIRE 16 -1 (1325 3225)(1575 3225);
WIRE 16 -1 (1325 3225)(1325 3175);
WIRE 16 -1 (1325 3175)(1575 3175);
WIRE 16 -1 (1325 3175)(1325 3125);
WIRE 16 -1 (1325 3125)(1575 3125);
WIRE 16 -1 (1325 3125)(1325 3075);
WIRE 16 -1 (1325 3075)(1575 3075);
WIRE 16 -1 (1325 3025)(1575 3025);
WIRE 16 -1 (1325 3075)(1325 3025);
WIRE 16 -1 (1325 3025)(1325 2975);
WIRE 16 -1 (1325 2975)(1575 2975);
WIRE 16 -1 (1325 2975)(1325 2925);
WIRE 16 -1 (1325 2925)(1575 2925);
WIRE 16 -1 (1325 2925)(1325 2875);
WIRE 16 -1 (1325 2875)(1575 2875);
WIRE 16 -1 (1325 2875)(1325 2825);
WIRE 16 -1 (1325 2825)(1575 2825);
WIRE 16 -1 (1325 2825)(1325 2775);
WIRE 16 -1 (1325 2775)(1575 2775);
WIRE 16 -1 (1325 2775)(1325 2725);
WIRE 16 -1 (1325 2725)(1575 2725);
WIRE 16 -1 (1325 2725)(1325 2675);
WIRE 16 -1 (1325 2675)(1575 2675);
WIRE 16 -1 (1325 2675)(1325 2625);
WIRE 16 -1 (1325 2625)(1575 2625);
WIRE 16 -1 (1325 2625)(1325 2575);
WIRE 16 -1 (1325 2575)(1575 2575);
WIRE 16 -1 (1325 2575)(1325 2525);
WIRE 16 -1 (1325 2525)(1575 2525);
WIRE 16 -1 (1325 2525)(1325 2475);
WIRE 16 -1 (1325 2475)(1575 2475);
WIRE 16 -1 (1325 2475)(1325 2425);
WIRE 16 -1 (1325 2425)(1575 2425);
WIRE 16 -1 (4225 825)(3975 825);
WIRE 16 -1 (4225 875)(3975 875);
WIRE 16 -1 (4225 875)(4225 825);
WIRE 16 -1 (4225 925)(3975 925);
WIRE 16 -1 (4225 925)(4225 875);
WIRE 16 -1 (4225 975)(3975 975);
WIRE 16 -1 (4225 975)(4225 925);
WIRE 16 -1 (4225 1025)(3975 1025);
WIRE 16 -1 (4225 1025)(4225 975);
WIRE 16 -1 (4225 1075)(3975 1075);
WIRE 16 -1 (4225 1075)(4225 1025);
WIRE 16 -1 (3975 1125)(4225 1125);
WIRE 16 -1 (4225 1125)(4225 1075);
WIRE 16 -1 (3975 1175)(4225 1175);
WIRE 16 -1 (4225 1175)(4225 1125);
WIRE 16 -1 (3975 1225)(4225 1225);
WIRE 16 -1 (4225 1225)(4225 1175);
WIRE 16 -1 (3975 1275)(4225 1275);
WIRE 16 -1 (4225 1275)(4225 1225);
WIRE 16 -1 (4225 1275)(4575 1275);
WIRE 16 -1 (1325 2025)(1575 2025);
WIRE 16 -1 (1325 2075)(1325 2025);
WIRE 16 -1 (1325 2075)(1575 2075);
WIRE 16 -1 (1325 1325)(1575 1325);
WIRE 16 -1 (1325 1375)(1325 1325);
WIRE 16 -1 (1325 1375)(1575 1375);
WIRE 16 -1 (1325 1425)(1325 1375);
WIRE 16 -1 (1325 1425)(1575 1425);
WIRE 16 -1 (1325 1475)(1325 1425);
WIRE 16 -1 (1325 1475)(1575 1475);
WIRE 16 -1 (1325 1475)(1325 1525);
WIRE 16 -1 (1325 1525)(1575 1525);
WIRE 16 -1 (1325 1775)(1575 1775);
WIRE 16 -1 (1325 1825)(1325 1775);
WIRE 16 -1 (1325 1825)(1575 1825);
WIRE 16 -1 (625 1825)(1325 1825);
WIRE 16 -1 (625 1700)(625 1825);
WIRE 16 -1 (-3050 1875)(-2800 1875);
WIRE 16 -1 (-3050 1925)(-3050 1875);
WIRE 16 -1 (-3050 1925)(-2800 1925);
WIRE 16 -1 (-3050 1975)(-3050 1925);
WIRE 16 -1 (-3050 1975)(-2800 1975);
WIRE 16 -1 (-3050 2025)(-3050 1975);
WIRE 16 -1 (-3050 2025)(-2800 2025);
WIRE 16 -1 (-3050 2075)(-3050 2025);
WIRE 16 -1 (-3050 2075)(-2800 2075);
WIRE 16 -1 (-3050 2125)(-3050 2075);
WIRE 16 -1 (-3050 2125)(-2800 2125);
WIRE 16 -1 (-3050 2175)(-3050 2125);
WIRE 16 -1 (-3050 2175)(-2800 2175);
WIRE 16 -1 (-3050 2225)(-3050 2175);
WIRE 16 -1 (-3050 2225)(-2800 2225);
WIRE 16 -1 (-3050 2275)(-3050 2225);
WIRE 16 -1 (-3050 2275)(-2800 2275);
WIRE 16 -1 (-3050 2325)(-3050 2275);
WIRE 16 -1 (-3050 2325)(-2800 2325);
WIRE 16 -1 (-3050 2375)(-3050 2325);
WIRE 16 -1 (-3050 2375)(-2800 2375);
WIRE 16 -1 (-3050 2425)(-3050 2375);
WIRE 16 -1 (-3050 2425)(-2800 2425);
WIRE 16 -1 (-3050 2475)(-3050 2425);
WIRE 16 -1 (-3050 2475)(-2800 2475);
WIRE 16 -1 (-3050 2525)(-3050 2475);
WIRE 16 -1 (-3050 2525)(-2800 2525);
WIRE 16 -1 (-3050 2575)(-3050 2525);
WIRE 16 -1 (-3050 2575)(-2800 2575);
WIRE 16 -1 (-3050 2625)(-3050 2575);
WIRE 16 -1 (-3050 2625)(-2800 2625);
WIRE 16 -1 (-3050 2675)(-3050 2625);
WIRE 16 -1 (-3050 2675)(-2800 2675);
WIRE 16 -1 (-3050 2725)(-3050 2675);
WIRE 16 -1 (-3050 2725)(-2800 2725);
WIRE 16 -1 (-3050 2775)(-3050 2725);
WIRE 16 -1 (-3050 2775)(-2800 2775);
WIRE 16 -1 (-3050 2825)(-3050 2775);
WIRE 16 -1 (-3050 2825)(-2800 2825);
WIRE 16 -1 (-3050 2875)(-3050 2825);
WIRE 16 -1 (-3050 2875)(-2800 2875);
WIRE 16 -1 (-3050 2925)(-3050 2875);
WIRE 16 -1 (-3050 2925)(-2800 2925);
WIRE 16 -1 (-3050 2975)(-3050 2925);
WIRE 16 -1 (-3050 2975)(-2800 2975);
WIRE 16 -1 (-3050 3025)(-3050 2975);
WIRE 16 -1 (-3050 3025)(-2800 3025);
WIRE 16 -1 (-3050 3075)(-3050 3025);
WIRE 16 -1 (-3050 3075)(-2800 3075);
WIRE 16 -1 (-3050 3125)(-3050 3075);
WIRE 16 -1 (-3050 3125)(-2800 3125);
WIRE 16 -1 (-3050 3175)(-3050 3125);
WIRE 16 -1 (-3050 3175)(-2800 3175);
WIRE 16 -1 (-3050 3225)(-3050 3175);
WIRE 16 -1 (-2800 3225)(-3050 3225);
WIRE 16 -1 (-3050 3275)(-3050 3225);
WIRE 16 -1 (-3050 3275)(-2800 3275);
WIRE 16 -1 (-3050 3325)(-3050 3275);
WIRE 16 -1 (-3050 3325)(-2800 3325);
WIRE 16 -1 (-3050 3375)(-3050 3325);
WIRE 16 -1 (-2800 3375)(-3050 3375);
WIRE 16 -1 (-3050 3425)(-3050 3375);
WIRE 16 -1 (-3050 3425)(-2800 3425);
WIRE 16 -1 (-3050 3475)(-3050 3425);
WIRE 16 -1 (-3050 3475)(-2800 3475);
WIRE 16 -1 (-3050 3525)(-3050 3475);
WIRE 16 -1 (-2800 3525)(-3050 3525);
WIRE 16 -1 (-3050 3575)(-3050 3525);
WIRE 16 -1 (-3050 3575)(-2800 3575);
WIRE 16 -1 (-3050 3625)(-3050 3575);
WIRE 16 -1 (-3050 3625)(-2800 3625);
WIRE 16 -1 (-3050 3675)(-3050 3625);
WIRE 16 -1 (-2800 3675)(-3050 3675);
WIRE 16 -1 (-3050 3725)(-3050 3675);
WIRE 16 -1 (-3050 3725)(-2800 3725);
WIRE 16 -1 (-3050 3775)(-3050 3725);
WIRE 16 -1 (-3050 3775)(-2800 3775);
WIRE 16 -1 (-3050 3825)(-3050 3775);
WIRE 16 -1 (-2800 3825)(-3050 3825);
WIRE 16 -1 (3975 2175)(4225 2175);
WIRE 16 -1 (3975 2225)(4225 2225);
WIRE 16 -1 (4225 2225)(4225 2175);
WIRE 16 -1 (3975 2275)(4225 2275);
WIRE 16 -1 (4225 2275)(4225 2225);
WIRE 16 -1 (3975 2325)(4225 2325);
WIRE 16 -1 (4225 2325)(4225 2275);
WIRE 16 -1 (3975 2375)(4225 2375);
WIRE 16 -1 (4225 2375)(4225 2325);
WIRE 16 -1 (3975 2425)(4225 2425);
WIRE 16 -1 (4225 2425)(4225 2375);
WIRE 16 -1 (3975 2475)(4225 2475);
WIRE 16 -1 (4225 2475)(4225 2425);
WIRE 16 -1 (3975 2525)(4225 2525);
WIRE 16 -1 (4225 2525)(4225 2475);
WIRE 16 -1 (3975 2575)(4225 2575);
WIRE 16 -1 (4225 2575)(4225 2525);
WIRE 16 -1 (3975 2625)(4225 2625);
WIRE 16 -1 (4225 2625)(4225 2575);
WIRE 16 -1 (3975 2675)(4225 2675);
WIRE 16 -1 (4225 2675)(4225 2625);
WIRE 16 -1 (3975 2725)(4225 2725);
WIRE 16 -1 (4225 2725)(4225 2675);
WIRE 16 -1 (3975 2775)(4225 2775);
WIRE 16 -1 (4225 2775)(4225 2725);
WIRE 16 -1 (3975 2825)(4225 2825);
WIRE 16 -1 (4225 2825)(4225 2775);
WIRE 16 -1 (3975 2875)(4225 2875);
WIRE 16 -1 (4225 2875)(4225 2825);
WIRE 16 -1 (3975 2925)(4225 2925);
WIRE 16 -1 (4225 2925)(4225 2875);
WIRE 16 -1 (3975 2975)(4225 2975);
WIRE 16 -1 (4225 2975)(4225 2925);
WIRE 16 -1 (3975 3025)(4225 3025);
WIRE 16 -1 (4225 3025)(4225 2975);
WIRE 16 -1 (3975 3075)(4225 3075);
WIRE 16 -1 (4225 3075)(4225 3025);
WIRE 16 -1 (3975 3125)(4225 3125);
WIRE 16 -1 (4225 3125)(4225 3075);
WIRE 16 -1 (4225 3175)(3975 3175);
WIRE 16 -1 (4225 3175)(4225 3125);
WIRE 16 -1 (4225 3225)(3975 3225);
WIRE 16 -1 (4225 3225)(4225 3175);
WIRE 16 -1 (4225 3275)(3975 3275);
WIRE 16 -1 (4225 3275)(4225 3225);
WIRE 16 -1 (4225 3325)(3975 3325);
WIRE 16 -1 (4225 3325)(4225 3275);
WIRE 16 -1 (4225 3375)(3975 3375);
WIRE 16 -1 (4225 3375)(4225 3325);
WIRE 16 -1 (4225 3425)(3975 3425);
WIRE 16 -1 (4225 3425)(4225 3375);
WIRE 16 -1 (4225 3475)(3975 3475);
WIRE 16 -1 (4225 3475)(4225 3425);
WIRE 16 -1 (4225 3525)(3975 3525);
WIRE 16 -1 (4225 3525)(4225 3475);
WIRE 16 -1 (4225 3575)(3975 3575);
WIRE 16 -1 (4225 3575)(4225 3525);
WIRE 16 -1 (4225 3625)(3975 3625);
WIRE 16 -1 (4225 3625)(4225 3575);
WIRE 16 -1 (4225 3675)(3975 3675);
WIRE 16 -1 (4225 3675)(4225 3625);
WIRE 16 -1 (4225 3725)(3975 3725);
WIRE 16 -1 (4225 3725)(4225 3675);
WIRE 16 -1 (4225 3775)(3975 3775);
WIRE 16 -1 (4225 3775)(4225 3725);
WIRE 16 -1 (4225 3825)(3975 3825);
WIRE 16 -1 (4225 3825)(4225 3775);
WIRE 16 -1 (4225 3875)(3975 3875);
WIRE 16 -1 (4225 3875)(4225 3825);
WIRE 16 -1 (4225 3925)(3975 3925);
WIRE 16 -1 (4225 3925)(4225 3875);
WIRE 16 -1 (4225 3975)(3975 3975);
WIRE 16 -1 (4225 3975)(4225 3925);
WIRE 16 -1 (4225 4025)(3975 4025);
WIRE 16 -1 (4225 4025)(4225 3975);
WIRE 16 -1 (4225 4075)(3975 4075);
WIRE 16 -1 (4225 4075)(4225 4025);
WIRE 16 -1 (3975 1975)(4225 1975);
WIRE 16 -1 (3975 1925)(4225 1925);
WIRE 16 -1 (4225 1975)(4225 1925);
WIRE 16 -1 (4225 1925)(4575 1925);
DOT 1 (1325 3425);
DOT 1 (-150 3225);
DOT 1 (1325 1825);
DOT 1 (-3050 1925);
DOT 1 (-3050 1975);
DOT 1 (-3050 2025);
DOT 1 (-3050 2075);
DOT 1 (-3050 2125);
DOT 1 (-3050 2175);
DOT 1 (-3050 2225);
DOT 1 (-3050 2275);
DOT 1 (-3050 2325);
DOT 1 (-3050 2375);
DOT 1 (-3050 2425);
DOT 1 (-3050 2475);
DOT 1 (-3050 2525);
DOT 1 (-3050 2575);
DOT 1 (-3050 2625);
DOT 1 (-3050 2675);
DOT 1 (-3050 2725);
DOT 1 (-3050 2775);
DOT 1 (-3050 2875);
DOT 1 (-3050 2925);
DOT 1 (-3050 2975);
DOT 1 (-3050 3025);
DOT 1 (-3050 3075);
DOT 1 (-3050 3125);
DOT 1 (-3050 3175);
DOT 1 (-3050 3225);
DOT 1 (-3050 3275);
DOT 1 (-3050 3325);
DOT 1 (-3050 3375);
DOT 1 (-3050 3425);
DOT 1 (-3050 3475);
DOT 1 (-3050 3525);
DOT 1 (-3050 3625);
DOT 1 (-3050 3675);
DOT 1 (-3050 3725);
DOT 1 (-3050 3775);
DOT 1 (-3050 3825);
DOT 1 (-150 2825);
DOT 1 (-150 3125);
DOT 1 (-150 3175);
DOT 1 (-150 3275);
DOT 1 (-150 3325);
DOT 1 (-150 3425);
DOT 1 (-150 3375);
DOT 1 (-150 3475);
DOT 1 (-150 3525);
DOT 1 (-150 3575);
DOT 1 (-150 3675);
DOT 1 (-150 3725);
DOT 1 (-150 3775);
DOT 1 (-150 3825);
DOT 1 (625 1825);
DOT 1 (1325 1375);
DOT 1 (1325 1425);
DOT 1 (1325 1525);
DOT 1 (1325 2075);
DOT 1 (1325 2475);
DOT 1 (1325 2525);
DOT 1 (1325 2575);
DOT 1 (1325 2625);
DOT 1 (1325 2675);
DOT 1 (1325 2725);
DOT 1 (1325 2775);
DOT 1 (1325 2825);
DOT 1 (1325 2875);
DOT 1 (1325 2925);
DOT 1 (1325 2975);
DOT 1 (1325 3075);
DOT 1 (1325 3125);
DOT 1 (1325 3175);
DOT 1 (1325 3225);
DOT 1 (1325 3275);
DOT 1 (1325 3325);
DOT 1 (1325 3375);
DOT 1 (1325 3475);
DOT 1 (1325 3525);
DOT 1 (1325 3575);
DOT 1 (1325 3675);
DOT 1 (1325 3625);
DOT 1 (1325 3725);
DOT 1 (1325 3825);
DOT 1 (4225 975);
DOT 1 (4225 925);
DOT 1 (4225 875);
DOT 1 (4225 1025);
DOT 1 (4225 1075);
DOT 1 (4225 1125);
DOT 1 (4225 1175);
DOT 1 (4225 1225);
DOT 1 (4225 1275);
DOT 1 (4225 1925);
DOT 1 (4225 2225);
DOT 1 (4225 2275);
DOT 1 (4225 2425);
DOT 1 (4225 2525);
DOT 1 (4225 2475);
DOT 1 (4225 2375);
DOT 1 (4225 2325);
DOT 1 (4225 2725);
DOT 1 (4225 2675);
DOT 1 (4225 2625);
DOT 1 (4225 2575);
DOT 1 (4225 2775);
DOT 1 (4225 2825);
DOT 1 (4225 3025);
DOT 1 (4225 2925);
DOT 1 (4225 2875);
DOT 1 (4225 2975);
DOT 1 (4225 3075);
DOT 1 (4225 3275);
DOT 1 (4225 3175);
DOT 1 (4225 3125);
DOT 1 (4225 3325);
DOT 1 (4225 3225);
DOT 1 (4225 3525);
DOT 1 (4225 3475);
DOT 1 (4225 3425);
DOT 1 (4225 3375);
DOT 1 (4225 3575);
DOT 1 (4225 3775);
DOT 1 (4225 3725);
DOT 1 (4225 3675);
DOT 1 (4225 3625);
DOT 1 (4225 3825);
DOT 1 (4225 3925);
DOT 1 (4225 3875);
DOT 1 (4225 4025);
DOT 1 (4225 4075);
DOT 1 (4225 3975);
DOT 1 (1325 1475);
DOT 1 (-3050 2825);
DOT 1 (-150 3075);
DOT 1 (-3050 3575);
DOT 1 (1325 3775);
DOT 1 (-150 2875);
DOT 1 (-150 2925);
DOT 1 (-150 2975);
DOT 1 (-150 3025);
DOT 1 (1325 3025);
QUIT
